# S9S_MB_2U (Grand Teton) — schematic netlist excerpt (pin names and nets, part order shuffled) for the footprints in the layout excerpt that follows; sources: Cadence DE-HDL packaged netlist, KiCad conversion of 03242023_DA0F0TMBIJ0_F0T_Motherboard_J_brd_V01_OCP.brd

R4211  Q_RES  200K 1% CHIP  pkg 0402LF  page 170 : A = P3V3_AUX ; B = FM_THERMAL_ALERT_N
R4400  Q_RES  33.2 1% CHIP  pkg 0402LF  page 121 : A = H_CPU1_THERMTRIP_VT_N ; B = H_CPU1_THERMTRIP_LVC1_N

(kicad_pcb
	(version 20260206)
	(generator "pcbnew")
	(generator_version "10.0")
	(general
		(thickness 1.6)
		(legacy_teardrops no)
	)
	(paper "A4")
	(title_block
		(title "03242023_DA0F0TMBIJ0_F0T_Motherboard_J_brd_V01_OCP.brd")
		(comment 1 "Grand Teton / footprints 239-240 of 6105")
	)
	(layers
		(0 "F.Cu" signal "TOP")
		(4 "In1.Cu" signal "GND")
		(6 "In2.Cu" signal "IN1")
		(8 "In3.Cu" signal "GND1")
		(10 "In4.Cu" signal "IN2")
		(12 "In5.Cu" signal "GND2")
		(14 "In6.Cu" signal "IN3")
		(16 "In7.Cu" signal "GND3")
		(18 "In8.Cu" signal "VCC")
		(20 "In9.Cu" signal "VCC1")
		(22 "In10.Cu" signal "GND4")
		(24 "In11.Cu" signal "IN4")
		(26 "In12.Cu" signal "GND5")
		(28 "In13.Cu" signal "IN5")
		(30 "In14.Cu" signal "GND6")
		(32 "In15.Cu" signal "IN6")
		(34 "In16.Cu" signal "GND7")
		(2 "B.Cu" signal "BOTTOM")
		(9 "F.Adhes" user "F.Adhesive")
		(11 "B.Adhes" user "B.Adhesive")
		(13 "F.Paste" user "Package Geometry/Pastemask Top")
		(15 "B.Paste" user "Package Geometry/Pastemask Bottom")
		(5 "F.SilkS" user "Ref Des/Silkscreen Top")
		(7 "B.SilkS" user "Ref Des/Silkscreen Bottom")
		(1 "F.Mask" user "Board Geometry/Soldermask Top")
		(3 "B.Mask" user "Board Geometry/Soldermask Bottom")
		(17 "Dwgs.User" user "User.Drawings")
		(19 "Cmts.User" user "User.Comments")
		(21 "Eco1.User" user "User.Eco1")
		(23 "Eco2.User" user "User.Eco2")
		(25 "Edge.Cuts" user "Board Geometry/Outline")
		(27 "Margin" user)
		(31 "F.CrtYd" user "Package Geometry/Place Bound Top")
		(29 "B.CrtYd" user "Package Geometry/Place Bound Bottom")
		(35 "F.Fab" user "Ref Des/Assembly Top")
		(33 "B.Fab" user "Ref Des/Assembly Bottom")
	)
	(footprint ""
		(layer "F.Cu")
		(at 366.678718 -417.14801 90)
		(property "Reference" "R4211"
			(at 0 0 90)
			(layer "F.SilkS")
			(hide yes)
			(effects
				(font
					(size 1.27 1.27)
				)
			)
		)
		(property "Value" ""
			(at 0 0 90)
			(layer "F.Fab")
			(effects
				(font
					(size 1.27 1.27)
				)
			)
		)
		(duplicate_pad_numbers_are_jumpers no)
		(fp_line
			(start 0.7874 -0.4064)
			(end 0.7874 0.4064)
			(stroke
				(width 0.1524)
				(type default)
			)
			(layer "F.SilkS")
		)
		(fp_line
			(start -0.7874 -0.4064)
			(end 0.7874 -0.4064)
			(stroke
				(width 0.1524)
				(type default)
			)
			(layer "F.SilkS")
		)
		(fp_line
			(start 0.7874 0.4064)
			(end -0.7874 0.4064)
			(stroke
				(width 0.1524)
				(type default)
			)
			(layer "F.SilkS")
		)
		(fp_line
			(start -0.7874 0.4064)
			(end -0.7874 -0.4064)
			(stroke
				(width 0.1524)
				(type default)
			)
			(layer "F.SilkS")
		)
		(fp_line
			(start -0.12065 -0.305054)
			(end -0.12065 -0.2794)
			(stroke
				(width 0.1)
				(type default)
			)
			(layer "F.Fab")
		)
		(fp_line
			(start -0.67945 -0.305054)
			(end -0.12065 -0.305054)
			(stroke
				(width 0.1)
				(type default)
			)
			(layer "F.Fab")
		)
		(fp_line
			(start 0.67945 -0.3048)
			(end 0.67945 0.3048)
			(stroke
				(width 0.1)
				(type default)
			)
			(layer "F.Fab")
		)
		(fp_line
			(start 0.12065 -0.3048)
			(end 0.67945 -0.3048)
			(stroke
				(width 0.1)
				(type default)
			)
			(layer "F.Fab")
		)
		(fp_line
			(start 0.12065 -0.2794)
			(end 0.12065 -0.3048)
			(stroke
				(width 0.1)
				(type default)
			)
			(layer "F.Fab")
		)
		(fp_line
			(start -0.12065 -0.2794)
			(end 0.12065 -0.2794)
			(stroke
				(width 0.1)
				(type default)
			)
			(layer "F.Fab")
		)
		(fp_line
			(start 0.120396 0.2794)
			(end -0.12065 0.2794)
			(stroke
				(width 0.1)
				(type default)
			)
			(layer "F.Fab")
		)
		(fp_line
			(start -0.12065 0.2794)
			(end -0.12065 0.3048)
			(stroke
				(width 0.1)
				(type default)
			)
			(layer "F.Fab")
		)
		(fp_line
			(start 0.67945 0.3048)
			(end 0.120396 0.3048)
			(stroke
				(width 0.1)
				(type default)
			)
			(layer "F.Fab")
		)
		(fp_line
			(start 0.120396 0.3048)
			(end 0.120396 0.2794)
			(stroke
				(width 0.1)
				(type default)
			)
			(layer "F.Fab")
		)
		(fp_line
			(start -0.12065 0.3048)
			(end -0.67945 0.3048)
			(stroke
				(width 0.1)
				(type default)
			)
			(layer "F.Fab")
		)
		(fp_line
			(start -0.67945 0.3048)
			(end -0.67945 -0.305054)
			(stroke
				(width 0.1)
				(type default)
			)
			(layer "F.Fab")
		)
		(pad "1" smd circle
			(at -0.40005 0 90)
			(size 0 0)
			(layers "F.Cu" "F.Mask" "F.Paste")
			(net "P3V3_AUX")
		)
		(pad "2" smd circle
			(at 0.40005 0 90)
			(size 0 0)
			(layers "F.Cu" "F.Mask" "F.Paste")
			(net "FM_THERMAL_ALERT_N")
		)
	)
	(footprint ""
		(layer "F.Cu")
		(at 126.67488 -92.674948 -90)
		(property "Reference" "R4400"
			(at 0 0 270)
			(layer "F.SilkS")
			(hide yes)
			(effects
				(font
					(size 1.27 1.27)
				)
			)
		)
		(property "Value" ""
			(at 0 0 270)
			(layer "F.Fab")
			(effects
				(font
					(size 1.27 1.27)
				)
			)
		)
		(duplicate_pad_numbers_are_jumpers no)
		(fp_line
			(start -0.7874 0.4064)
			(end -0.7874 -0.4064)
			(stroke
				(width 0.1524)
				(type default)
			)
			(layer "F.SilkS")
		)
		(fp_line
			(start 0.7874 0.4064)
			(end -0.7874 0.4064)
			(stroke
				(width 0.1524)
				(type default)
			)
			(layer "F.SilkS")
		)
		(fp_line
			(start -0.7874 -0.4064)
			(end 0.7874 -0.4064)
			(stroke
				(width 0.1524)
				(type default)
			)
			(layer "F.SilkS")
		)
		(fp_line
			(start 0.7874 -0.4064)
			(end 0.7874 0.4064)
			(stroke
				(width 0.1524)
				(type default)
			)
			(layer "F.SilkS")
		)
		(fp_line
			(start -0.67945 0.3048)
			(end -0.67945 -0.305054)
			(stroke
				(width 0.1)
				(type default)
			)
			(layer "F.Fab")
		)
		(fp_line
			(start -0.12065 0.3048)
			(end -0.67945 0.3048)
			(stroke
				(width 0.1)
				(type default)
			)
			(layer "F.Fab")
		)
		(fp_line
			(start 0.120396 0.3048)
			(end 0.120396 0.2794)
			(stroke
				(width 0.1)
				(type default)
			)
			(layer "F.Fab")
		)
		(fp_line
			(start 0.67945 0.3048)
			(end 0.120396 0.3048)
			(stroke
				(width 0.1)
				(type default)
			)
			(layer "F.Fab")
		)
		(fp_line
			(start -0.12065 0.2794)
			(end -0.12065 0.3048)
			(stroke
				(width 0.1)
				(type default)
			)
			(layer "F.Fab")
		)
		(fp_line
			(start 0.120396 0.2794)
			(end -0.12065 0.2794)
			(stroke
				(width 0.1)
				(type default)
			)
			(layer "F.Fab")
		)
		(fp_line
			(start -0.12065 -0.2794)
			(end 0.12065 -0.2794)
			(stroke
				(width 0.1)
				(type default)
			)
			(layer "F.Fab")
		)
		(fp_line
			(start 0.12065 -0.2794)
			(end 0.12065 -0.3048)
			(stroke
				(width 0.1)
				(type default)
			)
			(layer "F.Fab")
		)
		(fp_line
			(start 0.12065 -0.3048)
			(end 0.67945 -0.3048)
			(stroke
				(width 0.1)
				(type default)
			)
			(layer "F.Fab")
		)
		(fp_line
			(start 0.67945 -0.3048)
			(end 0.67945 0.3048)
			(stroke
				(width 0.1)
				(type default)
			)
			(layer "F.Fab")
		)
		(fp_line
			(start -0.67945 -0.305054)
			(end -0.12065 -0.305054)
			(stroke
				(width 0.1)
				(type default)
			)
			(layer "F.Fab")
		)
		(fp_line
			(start -0.12065 -0.305054)
			(end -0.12065 -0.2794)
			(stroke
				(width 0.1)
				(type default)
			)
			(layer "F.Fab")
		)
		(pad "1" smd circle
			(at -0.40005 0 270)
			(size 0 0)
			(layers "F.Cu" "F.Mask" "F.Paste")
			(net "H_CPU1_THERMTRIP_VT_N")
		)
		(pad "2" smd circle
			(at 0.40005 0 270)
			(size 0 0)
			(layers "F.Cu" "F.Mask" "F.Paste")
			(net "H_CPU1_THERMTRIP_LVC1_N")
		)
	)
)
